# S9S_MB_2U (Grand Teton) — schematic netlist excerpt (pin names and nets, part order shuffled) for the footprints in the layout excerpt that follows; sources: Cadence DE-HDL packaged netlist, KiCad conversion of 03242023_DA0F0TMBIJ0_F0T_Motherboard_J_brd_V01_OCP.brd

C2076  Q_CAP_DIFFBUS  DIFF BUS_0.22UF 6.3V 20% X6S  pkg C0201  page 181 : \1\ = P3E_PCH_NVS_TX_DN<0> ; \2\ = P3E_PCH_NVS_TX_C_DN<0>

Q53  MOSFET_NCH_GDS_ESD_PROTECTED  2N7002K IC  pkg SOT23_GDSXC  page 244
  D  = PWRGD_P3V3_AUX_R2
  G  = PWRGD_P3V3_AUX
  S  = GND

(kicad_pcb
	(version 20260206)
	(generator "pcbnew")
	(generator_version "10.0")
	(general
		(thickness 1.6)
		(legacy_teardrops no)
	)
	(paper "A4")
	(title_block
		(title "03242023_DA0F0TMBIJ0_F0T_Motherboard_J_brd_V01_OCP.brd")
		(comment 1 "Grand Teton / footprints 2920-2921 of 6105")
	)
	(layers
		(0 "F.Cu" signal "TOP")
		(4 "In1.Cu" signal "GND")
		(6 "In2.Cu" signal "IN1")
		(8 "In3.Cu" signal "GND1")
		(10 "In4.Cu" signal "IN2")
		(12 "In5.Cu" signal "GND2")
		(14 "In6.Cu" signal "IN3")
		(16 "In7.Cu" signal "GND3")
		(18 "In8.Cu" signal "VCC")
		(20 "In9.Cu" signal "VCC1")
		(22 "In10.Cu" signal "GND4")
		(24 "In11.Cu" signal "IN4")
		(26 "In12.Cu" signal "GND5")
		(28 "In13.Cu" signal "IN5")
		(30 "In14.Cu" signal "GND6")
		(32 "In15.Cu" signal "IN6")
		(34 "In16.Cu" signal "GND7")
		(2 "B.Cu" signal "BOTTOM")
		(9 "F.Adhes" user "F.Adhesive")
		(11 "B.Adhes" user "B.Adhesive")
		(13 "F.Paste" user "Package Geometry/Pastemask Top")
		(15 "B.Paste" user "Package Geometry/Pastemask Bottom")
		(5 "F.SilkS" user "Ref Des/Silkscreen Top")
		(7 "B.SilkS" user "Ref Des/Silkscreen Bottom")
		(1 "F.Mask" user "Board Geometry/Soldermask Top")
		(3 "B.Mask" user "Board Geometry/Soldermask Bottom")
		(17 "Dwgs.User" user "User.Drawings")
		(19 "Cmts.User" user "User.Comments")
		(21 "Eco1.User" user "User.Eco1")
		(23 "Eco2.User" user "User.Eco2")
		(25 "Edge.Cuts" user "Board Geometry/Outline")
		(27 "Margin" user)
		(31 "F.CrtYd" user "Package Geometry/Place Bound Top")
		(29 "B.CrtYd" user "Package Geometry/Place Bound Bottom")
		(35 "F.Fab" user "Ref Des/Assembly Top")
		(33 "B.Fab" user "Ref Des/Assembly Bottom")
	)
	(footprint ""
		(layer "F.Cu")
		(at 160.83788 -131.155948 90)
		(property "Reference" "Q53"
			(at 3.93573 -0.59436 0)
			(unlocked yes)
			(layer "F.SilkS")
			(effects
				(font
					(size 0.7874 0.5842)
					(thickness 0.1524)
				)
				(justify left)
			)
		)
		(property "Value" ""
			(at 0 0 90)
			(layer "F.Fab")
			(effects
				(font
					(size 1.27 1.27)
				)
			)
		)
		(duplicate_pad_numbers_are_jumpers no)
		(fp_line
			(start 1.603248 -1.500124)
			(end 1.603248 1.500124)
			(stroke
				(width 0.1524)
				(type default)
			)
			(layer "F.SilkS")
		)
		(fp_line
			(start -1.603248 -1.500124)
			(end 1.603248 -1.500124)
			(stroke
				(width 0.1524)
				(type default)
			)
			(layer "F.SilkS")
		)
		(fp_line
			(start 1.603248 1.500124)
			(end -1.603248 1.500124)
			(stroke
				(width 0.1524)
				(type default)
			)
			(layer "F.SilkS")
		)
		(fp_line
			(start -1.603248 1.500124)
			(end -1.603248 -1.500124)
			(stroke
				(width 0.1524)
				(type default)
			)
			(layer "F.SilkS")
		)
		(fp_line
			(start 0.700024 -1.500124)
			(end -0.700024 -1.500124)
			(stroke
				(width 0.1)
				(type default)
			)
			(layer "F.Fab")
		)
		(fp_line
			(start -0.700024 -1.500124)
			(end -0.700024 -1.169924)
			(stroke
				(width 0.1)
				(type default)
			)
			(layer "F.Fab")
		)
		(fp_line
			(start -0.700024 -1.169924)
			(end -1.249934 -1.169924)
			(stroke
				(width 0.1)
				(type default)
			)
			(layer "F.Fab")
		)
		(fp_line
			(start -1.249934 -1.169924)
			(end -1.249934 -0.729996)
			(stroke
				(width 0.1)
				(type default)
			)
			(layer "F.Fab")
		)
		(fp_line
			(start -0.6985 -0.729996)
			(end -0.6985 0.729996)
			(stroke
				(width 0.1)
				(type default)
			)
			(layer "F.Fab")
		)
		(fp_line
			(start -1.249934 -0.729996)
			(end -0.6985 -0.729996)
			(stroke
				(width 0.1)
				(type default)
			)
			(layer "F.Fab")
		)
		(fp_line
			(start 1.249934 -0.219964)
			(end 0.700024 -0.219964)
			(stroke
				(width 0.1)
				(type default)
			)
			(layer "F.Fab")
		)
		(fp_line
			(start 0.700024 -0.219964)
			(end 0.700024 -1.500124)
			(stroke
				(width 0.1)
				(type default)
			)
			(layer "F.Fab")
		)
		(fp_line
			(start 1.249934 0.219964)
			(end 1.249934 -0.219964)
			(stroke
				(width 0.1)
				(type default)
			)
			(layer "F.Fab")
		)
		(fp_line
			(start 0.700024 0.219964)
			(end 1.249934 0.219964)
			(stroke
				(width 0.1)
				(type default)
			)
			(layer "F.Fab")
		)
		(fp_line
			(start -0.6985 0.729996)
			(end -1.249934 0.729996)
			(stroke
				(width 0.1)
				(type default)
			)
			(layer "F.Fab")
		)
		(fp_line
			(start -1.249934 0.729996)
			(end -1.249934 1.169924)
			(stroke
				(width 0.1)
				(type default)
			)
			(layer "F.Fab")
		)
		(fp_line
			(start -0.700024 1.169924)
			(end -0.700024 1.500124)
			(stroke
				(width 0.1)
				(type default)
			)
			(layer "F.Fab")
		)
		(fp_line
			(start -1.249934 1.169924)
			(end -0.700024 1.169924)
			(stroke
				(width 0.1)
				(type default)
			)
			(layer "F.Fab")
		)
		(fp_line
			(start 0.700024 1.500124)
			(end 0.700024 0.219964)
			(stroke
				(width 0.1)
				(type default)
			)
			(layer "F.Fab")
		)
		(fp_line
			(start -0.700024 1.500124)
			(end 0.700024 1.500124)
			(stroke
				(width 0.1)
				(type default)
			)
			(layer "F.Fab")
		)
		(fp_rect
			(start -0.700024 1.500124)
			(end 0.700024 -1.500124)
			(stroke
				(width 0)
				(type default)
			)
			(fill no)
			(layer "F.Fab")
		)
		(pad "D" smd rect
			(at 0.999998 0)
			(size 0.8128 0.9144)
			(layers "F.Cu" "F.Mask" "F.Paste")
			(net "PWRGD_P3V3_AUX_R2")
		)
		(pad "G" smd rect
			(at -0.999998 -0.94996)
			(size 0.8128 0.9144)
			(layers "F.Cu" "F.Mask" "F.Paste")
			(net "PWRGD_P3V3_AUX")
		)
		(pad "S" smd rect
			(at -0.999998 0.94996)
			(size 0.8128 0.9144)
			(layers "F.Cu" "F.Mask" "F.Paste")
			(net "GND")
		)
	)
	(footprint ""
		(layer "F.Cu")
		(at 103.103426 -409.57754 90)
		(property "Reference" "C2076"
			(at 0 0 90)
			(layer "F.SilkS")
			(hide yes)
			(effects
				(font
					(size 1.27 1.27)
				)
			)
		)
		(property "Value" ""
			(at 0 0 90)
			(layer "F.Fab")
			(effects
				(font
					(size 1.27 1.27)
				)
			)
		)
		(duplicate_pad_numbers_are_jumpers no)
		(fp_line
			(start 0.299974 -0.150114)
			(end 0.299974 0.150114)
			(stroke
				(width 0.1)
				(type default)
			)
			(layer "F.Fab")
		)
		(fp_line
			(start -0.299974 -0.150114)
			(end 0.299974 -0.150114)
			(stroke
				(width 0.1)
				(type default)
			)
			(layer "F.Fab")
		)
		(fp_line
			(start 0.299974 0.150114)
			(end -0.299974 0.150114)
			(stroke
				(width 0.1)
				(type default)
			)
			(layer "F.Fab")
		)
		(fp_line
			(start -0.299974 0.150114)
			(end -0.299974 -0.150114)
			(stroke
				(width 0.1)
				(type default)
			)
			(layer "F.Fab")
		)
		(pad "1" smd rect
			(at -0.2667 0 90)
			(size 0.3048 0.381)
			(layers "F.Cu" "F.Mask" "F.Paste")
			(net "P3E_PCH_NVS_TX_DN<0>")
		)
		(pad "2" smd rect
			(at 0.2667 0 90)
			(size 0.3048 0.381)
			(layers "F.Cu" "F.Mask" "F.Paste")
			(net "P3E_PCH_NVS_TX_C_DN<0>")
		)
		(zone
			(layer "In1.Cu")
			(hatch none 0.5)
			(connect_pads
				(clearance 0)
			)
			(min_thickness 0.25)
			(keepout
				(tracks not_allowed)
				(vias allowed)
				(pads allowed)
				(copperpour not_allowed)
				(footprints allowed)
			)
			(placement
				(enabled no)
				(sheetname "")
			)
			(fill
				(thermal_gap 0.5)
				(thermal_bridge_width 0.5)
				(island_removal_mode 0)
			)
			(polygon
				(pts
					(arc
						(start 103.344726 -409.71724)
						(mid 103.322408 -409.663358)
						(end 103.268526 -409.64104)
					)
					(arc
						(start 102.938326 -409.64104)
						(mid 102.884444 -409.663358)
						(end 102.862126 -409.71724)
					)
					(arc
						(start 102.862126 -409.97124)
						(mid 102.884444 -410.025122)
						(end 102.938326 -410.04744)
					)
					(arc
						(start 103.268526 -410.04744)
						(mid 103.322408 -410.025122)
						(end 103.344726 -409.97124)
					)
				)
			)
		)
		(zone
			(layer "In1.Cu")
			(hatch none 0.5)
			(connect_pads
				(clearance 0)
			)
			(min_thickness 0.25)
			(keepout
				(tracks not_allowed)
				(vias allowed)
				(pads allowed)
				(copperpour not_allowed)
				(footprints allowed)
			)
			(placement
				(enabled no)
				(sheetname "")
			)
			(fill
				(thermal_gap 0.5)
				(thermal_bridge_width 0.5)
				(island_removal_mode 0)
			)
			(polygon
				(pts
					(arc
						(start 103.344726 -409.18384)
						(mid 103.322408 -409.129958)
						(end 103.268526 -409.10764)
					)
					(arc
						(start 102.938326 -409.10764)
						(mid 102.884444 -409.129958)
						(end 102.862126 -409.18384)
					)
					(arc
						(start 102.862126 -409.43784)
						(mid 102.884444 -409.491722)
						(end 102.938326 -409.51404)
					)
					(arc
						(start 103.268526 -409.51404)
						(mid 103.322408 -409.491722)
						(end 103.344726 -409.43784)
					)
				)
			)
		)
	)
)
